(kicad_pcb
	(version 20260206)
	(generator "pcbnew")
	(generator_version "10.0")
	(general
		(thickness 1.6)
		(legacy_teardrops no)
	)
	(paper "A4")
	(title_block
		(title "Wiwynn_Tioga_Pass_MB.brd")
		(comment 1 "Tioga Pass / footprints 2530-2536 of 4770")
	)
	(layers
		(0 "F.Cu" signal "TOP")
		(4 "In1.Cu" signal "L2GND")
		(6 "In2.Cu" signal "L3")
		(8 "In3.Cu" signal "L4GND")
		(10 "In4.Cu" signal "L5")
		(12 "In5.Cu" signal "L6GND")
		(14 "In6.Cu" signal "L7VCC")
		(16 "In7.Cu" signal "L8VCC")
		(18 "In8.Cu" signal "L9GND")
		(20 "In9.Cu" signal "L10")
		(22 "In10.Cu" signal "L11GND")
		(24 "In11.Cu" signal "L12")
		(26 "In12.Cu" signal "L13GND")
		(2 "B.Cu" signal "BOTTOM")
		(9 "F.Adhes" user "F.Adhesive")
		(11 "B.Adhes" user "B.Adhesive")
		(13 "F.Paste" user "Package Geometry/Pastemask Top")
		(15 "B.Paste" user "Package Geometry/Pastemask Bottom")
		(5 "F.SilkS" user "Ref Des/Silkscreen Top")
		(7 "B.SilkS" user "Ref Des/Silkscreen Bottom")
		(1 "F.Mask" user "Board Geometry/Soldermask Top")
		(3 "B.Mask" user "Board Geometry/Soldermask Bottom")
		(17 "Dwgs.User" user "User.Drawings")
		(19 "Cmts.User" user "User.Comments")
		(21 "Eco1.User" user "User.Eco1")
		(23 "Eco2.User" user "User.Eco2")
		(25 "Edge.Cuts" user "Board Geometry/Outline")
		(27 "Margin" user)
		(31 "F.CrtYd" user "Package Geometry/Place Bound Top")
		(29 "B.CrtYd" user "Package Geometry/Place Bound Bottom")
		(35 "F.Fab" user "Ref Des/Assembly Top")
		(33 "B.Fab" user "Ref Des/Assembly Bottom")
	)
	(footprint ""
		(layer "B.Cu")
		(at 104.5591 -149.8092 90)
		(property "Reference" "C5G103"
			(at -1.14681 0.76708 180)
			(unlocked yes)
			(layer "B.SilkS")
			(effects
				(font
					(size 0.7874 0.5842)
					(thickness 0.1524)
				)
				(justify mirror)
			)
		)
		(property "Value" ""
			(at 0 0 90)
			(layer "B.Fab")
			(effects
				(font
					(size 1.27 1.27)
				)
				(justify mirror)
			)
		)
		(duplicate_pad_numbers_are_jumpers no)
		(fp_rect
			(start -0.4953 -0.2032)
			(end 0.4953 1.6002)
			(stroke
				(width 0)
				(type default)
			)
			(fill no)
			(layer "B.CrtYd")
		)
		(fp_line
			(start 0.4953 -0.2032)
			(end -0.4953 -0.2032)
			(stroke
				(width 0.1)
				(type default)
			)
			(layer "B.Fab")
		)
		(fp_line
			(start -0.4953 -0.2032)
			(end -0.4953 1.6002)
			(stroke
				(width 0.1)
				(type default)
			)
			(layer "B.Fab")
		)
		(fp_line
			(start 0.4953 1.6002)
			(end 0.4953 -0.2032)
			(stroke
				(width 0.1)
				(type default)
			)
			(layer "B.Fab")
		)
		(fp_line
			(start -0.4953 1.6002)
			(end 0.4953 1.6002)
			(stroke
				(width 0.1)
				(type default)
			)
			(layer "B.Fab")
		)
		(pad "1" smd rect
			(at 0 0 270)
			(size 0.762 0.889)
			(layers "B.Cu" "B.Mask" "B.Paste")
			(net "PVDDQ_KLM")
		)
		(pad "2" smd rect
			(at 0 1.397 270)
			(size 0.762 0.889)
			(layers "B.Cu" "B.Mask" "B.Paste")
			(net "GND")
		)
		(zone
			(layer "B.Cu")
			(hatch none 0.5)
			(connect_pads
				(clearance 0)
			)
			(min_thickness 0.25)
			(keepout
				(tracks not_allowed)
				(vias allowed)
				(pads allowed)
				(copperpour not_allowed)
				(footprints allowed)
			)
			(placement
				(enabled no)
				(sheetname "")
			)
			(fill
				(thermal_gap 0.5)
				(thermal_bridge_width 0.5)
				(island_removal_mode 0)
			)
			(polygon
				(pts
					(xy 105.0036 -149.4282) (xy 105.5116 -149.4282) (xy 105.5116 -150.1902) (xy 105.0036 -150.1902)
				)
			)
		)
	)
	(footprint ""
		(layer "B.Cu")
		(at 473.122498 -135.78459 -90)
		(property "Reference" "C1W18"
			(at 0.8382 -0.67818 270)
			(unlocked yes)
			(layer "B.SilkS")
			(effects
				(font
					(size 0.4064 0.254)
					(thickness 0.1524)
				)
				(justify left mirror)
			)
		)
		(property "Value" ""
			(at 0 0 90)
			(layer "B.Fab")
			(effects
				(font
					(size 1.27 1.27)
				)
				(justify mirror)
			)
		)
		(duplicate_pad_numbers_are_jumpers no)
		(fp_poly
			(pts
				(xy -0.3048 -0.1016) (xy -0.3048 0.9906) (xy 0.3048 0.9906) (xy 0.3048 -0.1016)
			)
			(stroke
				(width 0)
				(type default)
			)
			(fill no)
			(layer "B.CrtYd")
		)
		(fp_line
			(start -0.3048 0.9906)
			(end -0.3048 -0.1016)
			(stroke
				(width 0.1)
				(type default)
			)
			(layer "B.Fab")
		)
		(fp_line
			(start 0.3048 0.9906)
			(end -0.3048 0.9906)
			(stroke
				(width 0.1)
				(type default)
			)
			(layer "B.Fab")
		)
		(fp_line
			(start -0.3048 -0.1016)
			(end 0.3048 -0.1016)
			(stroke
				(width 0.1)
				(type default)
			)
			(layer "B.Fab")
		)
		(fp_line
			(start 0.3048 -0.1016)
			(end 0.3048 0.9906)
			(stroke
				(width 0.1)
				(type default)
			)
			(layer "B.Fab")
		)
		(pad "1" smd rect
			(at 0 0 90)
			(size 0.508 0.508)
			(layers "B.Cu" "B.Mask" "B.Paste")
			(net "P3V3_STBY")
		)
		(pad "2" smd rect
			(at 0 0.889 90)
			(size 0.508 0.508)
			(layers "B.Cu" "B.Mask" "B.Paste")
			(net "GND")
		)
		(zone
			(layer "B.Cu")
			(hatch none 0.5)
			(connect_pads
				(clearance 0)
			)
			(min_thickness 0.25)
			(keepout
				(tracks not_allowed)
				(vias allowed)
				(pads allowed)
				(copperpour not_allowed)
				(footprints allowed)
			)
			(placement
				(enabled no)
				(sheetname "")
			)
			(fill
				(thermal_gap 0.5)
				(thermal_bridge_width 0.5)
				(island_removal_mode 0)
			)
			(polygon
				(pts
					(xy 472.487498 -135.53059) (xy 472.487498 -136.03859) (xy 472.868498 -136.03859) (xy 472.868498 -135.53059)
				)
			)
		)
		(zone
			(layer "B.Cu")
			(hatch none 0.5)
			(connect_pads
				(clearance 0)
			)
			(min_thickness 0.25)
			(keepout
				(tracks allowed)
				(vias not_allowed)
				(pads allowed)
				(copperpour not_allowed)
				(footprints allowed)
			)
			(placement
				(enabled no)
				(sheetname "")
			)
			(fill
				(thermal_gap 0.5)
				(thermal_bridge_width 0.5)
				(island_removal_mode 0)
			)
			(polygon
				(pts
					(xy 472.868498 -135.53059) (xy 472.868498 -136.03859) (xy 472.487498 -136.03859) (xy 472.487498 -135.53059)
				)
			)
		)
	)
	(footprint ""
		(layer "B.Cu")
		(at 500.246142 -43.04284 -90)
		(property "Reference" "C25W90"
			(at 0.8382 -0.67818 270)
			(unlocked yes)
			(layer "B.SilkS")
			(effects
				(font
					(size 0.4064 0.254)
					(thickness 0.1524)
				)
				(justify left mirror)
			)
		)
		(property "Value" ""
			(at 0 0 90)
			(layer "B.Fab")
			(effects
				(font
					(size 1.27 1.27)
				)
				(justify mirror)
			)
		)
		(duplicate_pad_numbers_are_jumpers no)
		(fp_poly
			(pts
				(xy -0.3048 -0.1016) (xy -0.3048 0.9906) (xy 0.3048 0.9906) (xy 0.3048 -0.1016)
			)
			(stroke
				(width 0)
				(type default)
			)
			(fill no)
			(layer "B.CrtYd")
		)
		(fp_line
			(start -0.3048 0.9906)
			(end -0.3048 -0.1016)
			(stroke
				(width 0.1)
				(type default)
			)
			(layer "B.Fab")
		)
		(fp_line
			(start 0.3048 0.9906)
			(end -0.3048 0.9906)
			(stroke
				(width 0.1)
				(type default)
			)
			(layer "B.Fab")
		)
		(fp_line
			(start -0.3048 -0.1016)
			(end 0.3048 -0.1016)
			(stroke
				(width 0.1)
				(type default)
			)
			(layer "B.Fab")
		)
		(fp_line
			(start 0.3048 -0.1016)
			(end 0.3048 0.9906)
			(stroke
				(width 0.1)
				(type default)
			)
			(layer "B.Fab")
		)
		(pad "1" smd rect
			(at 0 0 90)
			(size 0.508 0.508)
			(layers "B.Cu" "B.Mask" "B.Paste")
			(net "P5V_VGA_D")
		)
		(pad "2" smd rect
			(at 0 0.889 90)
			(size 0.508 0.508)
			(layers "B.Cu" "B.Mask" "B.Paste")
			(net "GND")
		)
		(zone
			(layer "B.Cu")
			(hatch none 0.5)
			(connect_pads
				(clearance 0)
			)
			(min_thickness 0.25)
			(keepout
				(tracks not_allowed)
				(vias allowed)
				(pads allowed)
				(copperpour not_allowed)
				(footprints allowed)
			)
			(placement
				(enabled no)
				(sheetname "")
			)
			(fill
				(thermal_gap 0.5)
				(thermal_bridge_width 0.5)
				(island_removal_mode 0)
			)
			(polygon
				(pts
					(xy 499.611142 -42.78884) (xy 499.611142 -43.29684) (xy 499.992142 -43.29684) (xy 499.992142 -42.78884)
				)
			)
		)
		(zone
			(layer "B.Cu")
			(hatch none 0.5)
			(connect_pads
				(clearance 0)
			)
			(min_thickness 0.25)
			(keepout
				(tracks allowed)
				(vias not_allowed)
				(pads allowed)
				(copperpour not_allowed)
				(footprints allowed)
			)
			(placement
				(enabled no)
				(sheetname "")
			)
			(fill
				(thermal_gap 0.5)
				(thermal_bridge_width 0.5)
				(island_removal_mode 0)
			)
			(polygon
				(pts
					(xy 499.992142 -42.78884) (xy 499.992142 -43.29684) (xy 499.611142 -43.29684) (xy 499.611142 -42.78884)
				)
			)
		)
	)
	(footprint ""
		(layer "B.Cu")
		(at 449.1736 -129.3622 180)
		(property "Reference" "C1M34"
			(at 0 0 0)
			(layer "B.SilkS")
			(hide yes)
			(effects
				(font
					(size 1.27 1.27)
				)
				(justify mirror)
			)
		)
		(property "Value" ""
			(at 0 0 0)
			(layer "B.Fab")
			(effects
				(font
					(size 1.27 1.27)
				)
				(justify mirror)
			)
		)
		(duplicate_pad_numbers_are_jumpers no)
		(fp_poly
			(pts
				(xy -0.3048 -0.1016) (xy -0.3048 0.9906) (xy 0.3048 0.9906) (xy 0.3048 -0.1016)
			)
			(stroke
				(width 0)
				(type default)
			)
			(fill no)
			(layer "B.CrtYd")
		)
		(fp_line
			(start 0.3048 0.9906)
			(end -0.3048 0.9906)
			(stroke
				(width 0.1)
				(type default)
			)
			(layer "B.Fab")
		)
		(fp_line
			(start 0.3048 -0.1016)
			(end 0.3048 0.9906)
			(stroke
				(width 0.1)
				(type default)
			)
			(layer "B.Fab")
		)
		(fp_line
			(start -0.3048 0.9906)
			(end -0.3048 -0.1016)
			(stroke
				(width 0.1)
				(type default)
			)
			(layer "B.Fab")
		)
		(fp_line
			(start -0.3048 -0.1016)
			(end 0.3048 -0.1016)
			(stroke
				(width 0.1)
				(type default)
			)
			(layer "B.Fab")
		)
		(pad "1" smd rect
			(at 0 0)
			(size 0.508 0.508)
			(layers "B.Cu" "B.Mask" "B.Paste")
			(net "P3V3_STBY")
		)
		(pad "2" smd rect
			(at 0 0.889)
			(size 0.508 0.508)
			(layers "B.Cu" "B.Mask" "B.Paste")
			(net "GND")
		)
		(zone
			(layer "B.Cu")
			(hatch none 0.5)
			(connect_pads
				(clearance 0)
			)
			(min_thickness 0.25)
			(keepout
				(tracks not_allowed)
				(vias allowed)
				(pads allowed)
				(copperpour not_allowed)
				(footprints allowed)
			)
			(placement
				(enabled no)
				(sheetname "")
			)
			(fill
				(thermal_gap 0.5)
				(thermal_bridge_width 0.5)
				(island_removal_mode 0)
			)
			(polygon
				(pts
					(xy 448.9196 -129.9972) (xy 449.4276 -129.9972) (xy 449.4276 -129.6162) (xy 448.9196 -129.6162)
				)
			)
		)
		(zone
			(layer "B.Cu")
			(hatch none 0.5)
			(connect_pads
				(clearance 0)
			)
			(min_thickness 0.25)
			(keepout
				(tracks allowed)
				(vias not_allowed)
				(pads allowed)
				(copperpour not_allowed)
				(footprints allowed)
			)
			(placement
				(enabled no)
				(sheetname "")
			)
			(fill
				(thermal_gap 0.5)
				(thermal_bridge_width 0.5)
				(island_removal_mode 0)
			)
			(polygon
				(pts
					(xy 448.9196 -129.6162) (xy 449.4276 -129.6162) (xy 449.4276 -129.9972) (xy 448.9196 -129.9972)
				)
			)
		)
	)
	(footprint ""
		(layer "B.Cu")
		(at 407.0858 -119.4816)
		(property "Reference" "C2M9"
			(at 0 0 0)
			(layer "B.SilkS")
			(hide yes)
			(effects
				(font
					(size 1.27 1.27)
				)
				(justify mirror)
			)
		)
		(property "Value" ""
			(at 0 0 0)
			(layer "B.Fab")
			(effects
				(font
					(size 1.27 1.27)
				)
				(justify mirror)
			)
		)
		(duplicate_pad_numbers_are_jumpers no)
		(fp_poly
			(pts
				(xy -0.3048 -0.1016) (xy -0.3048 0.9906) (xy 0.3048 0.9906) (xy 0.3048 -0.1016)
			)
			(stroke
				(width 0)
				(type default)
			)
			(fill no)
			(layer "B.CrtYd")
		)
		(fp_line
			(start -0.3048 -0.1016)
			(end 0.3048 -0.1016)
			(stroke
				(width 0.1)
				(type default)
			)
			(layer "B.Fab")
		)
		(fp_line
			(start -0.3048 0.9906)
			(end -0.3048 -0.1016)
			(stroke
				(width 0.1)
				(type default)
			)
			(layer "B.Fab")
		)
		(fp_line
			(start 0.3048 -0.1016)
			(end 0.3048 0.9906)
			(stroke
				(width 0.1)
				(type default)
			)
			(layer "B.Fab")
		)
		(fp_line
			(start 0.3048 0.9906)
			(end -0.3048 0.9906)
			(stroke
				(width 0.1)
				(type default)
			)
			(layer "B.Fab")
		)
		(pad "1" smd rect
			(at 0 0 180)
			(size 0.508 0.508)
			(layers "B.Cu" "B.Mask" "B.Paste")
			(net "P1V05_PCH_STBY_WM26_PLL")
		)
		(pad "2" smd rect
			(at 0 0.889 180)
			(size 0.508 0.508)
			(layers "B.Cu" "B.Mask" "B.Paste")
			(net "GND")
		)
		(zone
			(layer "B.Cu")
			(hatch none 0.5)
			(connect_pads
				(clearance 0)
			)
			(min_thickness 0.25)
			(keepout
				(tracks allowed)
				(vias not_allowed)
				(pads allowed)
				(copperpour not_allowed)
				(footprints allowed)
			)
			(placement
				(enabled no)
				(sheetname "")
			)
			(fill
				(thermal_gap 0.5)
				(thermal_bridge_width 0.5)
				(island_removal_mode 0)
			)
			(polygon
				(pts
					(xy 407.3398 -119.2276) (xy 406.8318 -119.2276) (xy 406.8318 -118.8466) (xy 407.3398 -118.8466)
				)
			)
		)
		(zone
			(layer "B.Cu")
			(hatch none 0.5)
			(connect_pads
				(clearance 0)
			)
			(min_thickness 0.25)
			(keepout
				(tracks not_allowed)
				(vias allowed)
				(pads allowed)
				(copperpour not_allowed)
				(footprints allowed)
			)
			(placement
				(enabled no)
				(sheetname "")
			)
			(fill
				(thermal_gap 0.5)
				(thermal_bridge_width 0.5)
				(island_removal_mode 0)
			)
			(polygon
				(pts
					(xy 407.3398 -118.8466) (xy 406.8318 -118.8466) (xy 406.8318 -119.2276) (xy 407.3398 -119.2276)
				)
			)
		)
	)
	(footprint ""
		(layer "B.Cu")
		(at 433.7685 -17.399 90)
		(property "Reference" "R9G28"
			(at 0 0 90)
			(layer "B.SilkS")
			(hide yes)
			(effects
				(font
					(size 1.27 1.27)
				)
				(justify mirror)
			)
		)
		(property "Value" ""
			(at 0 0 90)
			(layer "B.Fab")
			(effects
				(font
					(size 1.27 1.27)
				)
				(justify mirror)
			)
		)
		(duplicate_pad_numbers_are_jumpers no)
		(fp_poly
			(pts
				(xy 0.2794 -0.1016) (xy -0.2794 -0.1016) (xy -0.2794 0.9906) (xy 0.2794 0.9906)
			)
			(stroke
				(width 0)
				(type default)
			)
			(fill no)
			(layer "B.CrtYd")
		)
		(fp_line
			(start 0.2794 -0.1016)
			(end 0.2794 0.9906)
			(stroke
				(width 0.1)
				(type default)
			)
			(layer "B.Fab")
		)
		(fp_line
			(start -0.2794 -0.1016)
			(end 0.2794 -0.1016)
			(stroke
				(width 0.1)
				(type default)
			)
			(layer "B.Fab")
		)
		(fp_line
			(start 0.2794 0.9906)
			(end -0.2794 0.9906)
			(stroke
				(width 0.1)
				(type default)
			)
			(layer "B.Fab")
		)
		(fp_line
			(start -0.2794 0.9906)
			(end -0.2794 -0.1016)
			(stroke
				(width 0.1)
				(type default)
			)
			(layer "B.Fab")
		)
		(pad "1" smd rect
			(at 0 0 270)
			(size 0.508 0.508)
			(layers "B.Cu" "B.Mask" "B.Paste")
			(net "H_CPU1_KLM_MEMHOT_LVT3_R_N")
		)
		(pad "2" smd rect
			(at 0 0.889 270)
			(size 0.508 0.508)
			(layers "B.Cu" "B.Mask" "B.Paste")
			(net "H_CPU1_MEMKLM_MEMHOT_LVT3_K_N")
		)
		(zone
			(layer "B.Cu")
			(hatch none 0.5)
			(connect_pads
				(clearance 0)
			)
			(min_thickness 0.25)
			(keepout
				(tracks allowed)
				(vias not_allowed)
				(pads allowed)
				(copperpour not_allowed)
				(footprints allowed)
			)
			(placement
				(enabled no)
				(sheetname "")
			)
			(fill
				(thermal_gap 0.5)
				(thermal_bridge_width 0.5)
				(island_removal_mode 0)
			)
			(polygon
				(pts
					(xy 434.0225 -17.653) (xy 434.0225 -17.145) (xy 434.4035 -17.145) (xy 434.4035 -17.653)
				)
			)
		)
		(zone
			(layer "B.Cu")
			(hatch none 0.5)
			(connect_pads
				(clearance 0)
			)
			(min_thickness 0.25)
			(keepout
				(tracks not_allowed)
				(vias allowed)
				(pads allowed)
				(copperpour not_allowed)
				(footprints allowed)
			)
			(placement
				(enabled no)
				(sheetname "")
			)
			(fill
				(thermal_gap 0.5)
				(thermal_bridge_width 0.5)
				(island_removal_mode 0)
			)
			(polygon
				(pts
					(xy 434.4035 -17.653) (xy 434.4035 -17.145) (xy 434.0225 -17.145) (xy 434.0225 -17.653)
				)
			)
		)
	)
	(footprint ""
		(layer "B.Cu")
		(at 465.595208 -147.955254 180)
		(property "Reference" "R1L13"
			(at 0 0 0)
			(layer "B.SilkS")
			(hide yes)
			(effects
				(font
					(size 1.27 1.27)
				)
				(justify mirror)
			)
		)
		(property "Value" ""
			(at 0 0 0)
			(layer "B.Fab")
			(effects
				(font
					(size 1.27 1.27)
				)
				(justify mirror)
			)
		)
		(duplicate_pad_numbers_are_jumpers no)
		(fp_poly
			(pts
				(xy 0.2794 -0.1016) (xy -0.2794 -0.1016) (xy -0.2794 0.9906) (xy 0.2794 0.9906)
			)
			(stroke
				(width 0)
				(type default)
			)
			(fill no)
			(layer "B.CrtYd")
		)
		(fp_line
			(start 0.2794 0.9906)
			(end -0.2794 0.9906)
			(stroke
				(width 0.1)
				(type default)
			)
			(layer "B.Fab")
		)
		(fp_line
			(start 0.2794 -0.1016)
			(end 0.2794 0.9906)
			(stroke
				(width 0.1)
				(type default)
			)
			(layer "B.Fab")
		)
		(fp_line
			(start -0.2794 0.9906)
			(end -0.2794 -0.1016)
			(stroke
				(width 0.1)
				(type default)
			)
			(layer "B.Fab")
		)
		(fp_line
			(start -0.2794 -0.1016)
			(end 0.2794 -0.1016)
			(stroke
				(width 0.1)
				(type default)
			)
			(layer "B.Fab")
		)
		(pad "1" smd rect
			(at 0 0)
			(size 0.508 0.508)
			(layers "B.Cu" "B.Mask" "B.Paste")
			(net "XDP_SYSPWROK")
		)
		(pad "2" smd rect
			(at 0 0.889)
			(size 0.508 0.508)
			(layers "B.Cu" "B.Mask" "B.Paste")
			(net "P3V3_STBY")
		)
		(zone
			(layer "B.Cu")
			(hatch none 0.5)
			(connect_pads
				(clearance 0)
			)
			(min_thickness 0.25)
			(keepout
				(tracks not_allowed)
				(vias allowed)
				(pads allowed)
				(copperpour not_allowed)
				(footprints allowed)
			)
			(placement
				(enabled no)
				(sheetname "")
			)
			(fill
				(thermal_gap 0.5)
				(thermal_bridge_width 0.5)
				(island_removal_mode 0)
			)
			(polygon
				(pts
					(xy 465.341208 -148.590254) (xy 465.849208 -148.590254) (xy 465.849208 -148.209254) (xy 465.341208 -148.209254)
				)
			)
		)
		(zone
			(layer "B.Cu")
			(hatch none 0.5)
			(connect_pads
				(clearance 0)
			)
			(min_thickness 0.25)
			(keepout
				(tracks allowed)
				(vias not_allowed)
				(pads allowed)
				(copperpour not_allowed)
				(footprints allowed)
			)
			(placement
				(enabled no)
				(sheetname "")
			)
			(fill
				(thermal_gap 0.5)
				(thermal_bridge_width 0.5)
				(island_removal_mode 0)
			)
			(polygon
				(pts
					(xy 465.341208 -148.209254) (xy 465.849208 -148.209254) (xy 465.849208 -148.590254) (xy 465.341208 -148.590254)
				)
			)
		)
	)
)
